(kicad_pcb
	(version 20260206)
	(generator "pcbnew")
	(generator_version "10.0")
	(general
		(thickness 1.6)
		(legacy_teardrops no)
	)
	(paper "A4")
	(title_block
		(title "pdpb — Lightning_PDPB_BRD.brd")
		(comment 1 "Lightning (Wiwynn / Facebook NVMe JBOF) / footprints 498-499 of 1140")
	)
	(layers
		(0 "F.Cu" signal "TOP")
		(4 "In1.Cu" signal "L2GND")
		(6 "In2.Cu" signal "L3")
		(8 "In3.Cu" signal "L4VCC")
		(10 "In4.Cu" signal "L5VCC")
		(12 "In5.Cu" signal "L6")
		(14 "In6.Cu" signal "L7GND")
		(2 "B.Cu" signal "BOTTOM")
		(9 "F.Adhes" user "F.Adhesive")
		(11 "B.Adhes" user "B.Adhesive")
		(13 "F.Paste" user "Package Geometry/Pastemask Top")
		(15 "B.Paste" user "Package Geometry/Pastemask Bottom")
		(5 "F.SilkS" user "Ref Des/Silkscreen Top")
		(7 "B.SilkS" user "Ref Des/Silkscreen Bottom")
		(1 "F.Mask" user "Board Geometry/Soldermask Top")
		(3 "B.Mask" user "Board Geometry/Soldermask Bottom")
		(17 "Dwgs.User" user "User.Drawings")
		(19 "Cmts.User" user "User.Comments")
		(21 "Eco1.User" user "User.Eco1")
		(23 "Eco2.User" user "User.Eco2")
		(25 "Edge.Cuts" user "Board Geometry/Outline")
		(27 "Margin" user)
		(31 "F.CrtYd" user "Package Geometry/Place Bound Top")
		(29 "B.CrtYd" user "Package Geometry/Place Bound Bottom")
		(35 "F.Fab" user "Ref Des/Assembly Top")
		(33 "B.Fab" user "Ref Des/Assembly Bottom")
	)
	(footprint ""
		(layer "F.Cu")
		(at 93.98 -431.8 90)
		(property "Reference" "EU1"
			(at 0 0 90)
			(layer "F.SilkS")
			(hide yes)
			(effects
				(font
					(size 1.27 1.27)
				)
			)
		)
		(property "Value" "9ZXL1231AKLFT-GP"
			(at -6.5278 -7.2009 90)
			(unlocked yes)
			(layer "F.Fab")
			(hide yes)
			(effects
				(font
					(size 1.016 1.016)
					(thickness 0.1524)
				)
			)
		)
		(property "Device Type" "QFN64G9-G6D25H40"
			(at -6.5278 -8.7249 90)
			(unlocked yes)
			(layer "F.Fab")
			(hide yes)
			(effects
				(font
					(size 1.016 1.016)
					(thickness 0.1524)
				)
			)
		)
		(duplicate_pad_numbers_are_jumpers no)
		(fp_line
			(start 1.7526 -5.71881)
			(end 1.7526 -5.21081)
			(stroke
				(width 0.1524)
				(type default)
			)
			(layer "F.SilkS")
		)
		(fp_line
			(start -3.2639 -5.71881)
			(end -3.2639 -5.21081)
			(stroke
				(width 0.1524)
				(type default)
			)
			(layer "F.SilkS")
		)
		(fp_line
			(start -3.9878 -5.5118)
			(end -5.5118 -5.5118)
			(stroke
				(width 0.1524)
				(type default)
			)
			(layer "F.SilkS")
		)
		(fp_line
			(start -5.5118 -5.5118)
			(end -5.5118 -3.9243)
			(stroke
				(width 0.1524)
				(type default)
			)
			(layer "F.SilkS")
		)
		(fp_line
			(start -0.74041 -5.21081)
			(end -0.74041 -5.97281)
			(stroke
				(width 0.1524)
				(type default)
			)
			(layer "F.SilkS")
		)
		(fp_line
			(start -5.97281 -2.2606)
			(end -5.21081 -2.2606)
			(stroke
				(width 0.1524)
				(type default)
			)
			(layer "F.SilkS")
		)
		(fp_line
			(start 5.21081 -1.778)
			(end 5.97281 -1.778)
			(stroke
				(width 0.1524)
				(type default)
			)
			(layer "F.SilkS")
		)
		(fp_line
			(start -5.21081 0.254)
			(end -5.71881 0.254)
			(stroke
				(width 0.1524)
				(type default)
			)
			(layer "F.SilkS")
		)
		(fp_line
			(start 5.71881 0.7112)
			(end 5.21081 0.7112)
			(stroke
				(width 0.1524)
				(type default)
			)
			(layer "F.SilkS")
		)
		(fp_line
			(start -5.97281 2.7432)
			(end -5.21081 2.7432)
			(stroke
				(width 0.1524)
				(type default)
			)
			(layer "F.SilkS")
		)
		(fp_line
			(start 5.21081 3.22961)
			(end 5.97281 3.22961)
			(stroke
				(width 0.1524)
				(type default)
			)
			(layer "F.SilkS")
		)
		(fp_line
			(start -5.4991 4.1148)
			(end -5.4991 5.5118)
			(stroke
				(width 0.1524)
				(type default)
			)
			(layer "F.SilkS")
		)
		(fp_line
			(start 2.2352 5.21081)
			(end 2.2352 5.71881)
			(stroke
				(width 0.1524)
				(type default)
			)
			(layer "F.SilkS")
		)
		(fp_line
			(start -2.7432 5.21081)
			(end -2.7432 5.71881)
			(stroke
				(width 0.1524)
				(type default)
			)
			(layer "F.SilkS")
		)
		(fp_line
			(start 5.5118 5.4991)
			(end 5.5118 3.9878)
			(stroke
				(width 0.1524)
				(type default)
			)
			(layer "F.SilkS")
		)
		(fp_line
			(start 4.0767 5.4991)
			(end 5.5118 5.4991)
			(stroke
				(width 0.1524)
				(type default)
			)
			(layer "F.SilkS")
		)
		(fp_line
			(start -5.4991 5.5118)
			(end -4.2037 5.5118)
			(stroke
				(width 0.1524)
				(type default)
			)
			(layer "F.SilkS")
		)
		(fp_line
			(start -0.7366 5.97281)
			(end -0.7366 5.21081)
			(stroke
				(width 0.1524)
				(type default)
			)
			(layer "F.SilkS")
		)
		(fp_poly
			(pts
				(xy 5.481828 -4.084828) (xy 4.05511 -5.5118) (xy 5.481828 -5.5118)
			)
			(stroke
				(width 0)
				(type default)
			)
			(fill yes)
			(layer "F.SilkS")
		)
		(fp_rect
			(start -4.4958 4.4958)
			(end 4.4958 -4.4958)
			(stroke
				(width 0)
				(type default)
			)
			(fill no)
			(layer "F.CrtYd")
		)
		(fp_poly
			(pts
				(xy -5.5118 5.5118) (xy -5.5118 -5.5118) (xy 5.5118 -5.5118) (xy 5.5118 -0.5461) (xy 4.4958 -0.5461)
				(xy 4.4958 -4.4958) (xy -4.4958 -4.4958) (xy -4.4958 4.4958) (xy 4.4958 4.4958) (xy 4.4958 -0.5334)
				(xy 5.5118 -0.5334) (xy 5.5118 5.5118)
			)
			(stroke
				(width 0)
				(type default)
			)
			(fill no)
			(layer "F.CrtYd")
		)
		(fp_rect
			(start -5.5118 5.5118)
			(end 5.5118 -5.5118)
			(stroke
				(width 0)
				(type default)
			)
			(fill no)
			(layer "F.Fab")
		)
		(pad "1" smd rect
			(at 3.75031 -4.550918 90)
			(size 0.3048 0.9144)
			(layers "F.Cu" "F.Mask" "F.Paste")
			(net "VDDA_1")
		)
		(pad "2" smd rect
			(at 3.24993 -4.42341 90)
			(size 0.3048 1.1684)
			(layers "F.Cu" "F.Mask" "F.Paste")
			(net "GND")
		)
		(pad "3" smd rect
			(at 2.74955 -4.42341 90)
			(size 0.3048 1.1684)
			(layers "F.Cu" "F.Mask" "F.Paste")
			(net "Net_1332")
		)
		(pad "4" smd rect
			(at 2.25044 -4.42341 90)
			(size 0.3048 1.1684)
			(layers "F.Cu" "F.Mask" "F.Paste")
			(net "CLK_BUF_EU1_100M_133M#")
		)
		(pad "5" smd rect
			(at 1.75006 -4.42341 90)
			(size 0.3048 1.1684)
			(layers "F.Cu" "F.Mask" "F.Paste")
			(net "CLK_BUF_EU1_HIBW_BYPM_LOBW#")
		)
		(pad "6" smd rect
			(at 1.24968 -4.42341 90)
			(size 0.3048 1.1684)
			(layers "F.Cu" "F.Mask" "F.Paste")
			(net "P3V3_PG")
		)
		(pad "7" smd rect
			(at 0.75057 -4.42341 90)
			(size 0.3048 1.1684)
			(layers "F.Cu" "F.Mask" "F.Paste")
			(net "GND")
		)
		(pad "8" smd rect
			(at 0.25019 -4.42341 90)
			(size 0.3048 1.1684)
			(layers "F.Cu" "F.Mask" "F.Paste")
			(net "VDDR_1")
		)
		(pad "9" smd rect
			(at -0.25019 -4.42341 90)
			(size 0.3048 1.1684)
			(layers "F.Cu" "F.Mask" "F.Paste")
			(net "PE_100M_CLK4_P")
		)
		(pad "10" smd rect
			(at -0.75057 -4.42341 90)
			(size 0.3048 1.1684)
			(layers "F.Cu" "F.Mask" "F.Paste")
			(net "PE_100M_CLK4_N")
		)
		(pad "11" smd rect
			(at -1.24968 -4.42341 90)
			(size 0.3048 1.1684)
			(layers "F.Cu" "F.Mask" "F.Paste")
			(net "CLK_BUF_EU1_SMB_A0_TRI")
		)
		(pad "12" smd rect
			(at -1.75006 -4.42341 90)
			(size 0.3048 1.1684)
			(layers "F.Cu" "F.Mask" "F.Paste")
			(net "I2C_SDA_BUF_9_EU1_R")
		)
		(pad "13" smd rect
			(at -2.25044 -4.42341 90)
			(size 0.3048 1.1684)
			(layers "F.Cu" "F.Mask" "F.Paste")
			(net "I2C_SCL_BUF_9_EU1_R")
		)
		(pad "14" smd rect
			(at -2.74955 -4.42341 90)
			(size 0.3048 1.1684)
			(layers "F.Cu" "F.Mask" "F.Paste")
			(net "CLK_BUF_EU1_SMB_A1_TRI")
		)
		(pad "15" smd rect
			(at -3.24993 -4.42341 90)
			(size 0.3048 1.1684)
			(layers "F.Cu" "F.Mask" "F.Paste")
			(net "Net_1338")
		)
		(pad "16" smd rect
			(at -3.75031 -4.550918 90)
			(size 0.3048 0.9144)
			(layers "F.Cu" "F.Mask" "F.Paste")
			(net "Net_1337")
		)
		(pad "17" smd rect
			(at -4.550918 -3.75031 90)
			(size 0.9144 0.3048)
			(layers "F.Cu" "F.Mask" "F.Paste")
			(net "PE_CLK_100M_DR10_2_R_P")
		)
		(pad "18" smd rect
			(at -4.42341 -3.24993 90)
			(size 1.1684 0.3048)
			(layers "F.Cu" "F.Mask" "F.Paste")
			(net "PE_CLK_100M_DR10_2_R_N")
		)
		(pad "19" smd rect
			(at -4.42341 -2.74955 90)
			(size 1.1684 0.3048)
			(layers "F.Cu" "F.Mask" "F.Paste")
			(net "SSD_PRSNT10")
		)
		(pad "20" smd rect
			(at -4.42341 -2.25044 90)
			(size 1.1684 0.3048)
			(layers "F.Cu" "F.Mask" "F.Paste")
			(net "SSD10_CLK0_OE_R_N")
		)
		(pad "21" smd rect
			(at -4.42341 -1.75006 90)
			(size 1.1684 0.3048)
			(layers "F.Cu" "F.Mask" "F.Paste")
			(net "PE_CLK_100M_DR10_1_R_P")
		)
		(pad "22" smd rect
			(at -4.42341 -1.24968 90)
			(size 1.1684 0.3048)
			(layers "F.Cu" "F.Mask" "F.Paste")
			(net "PE_CLK_100M_DR10_1_R_N")
		)
		(pad "23" smd rect
			(at -4.42341 -0.75057 90)
			(size 1.1684 0.3048)
			(layers "F.Cu" "F.Mask" "F.Paste")
			(net "GND")
		)
		(pad "24" smd rect
			(at -4.42341 -0.25019 90)
			(size 1.1684 0.3048)
			(layers "F.Cu" "F.Mask" "F.Paste")
			(net "VDD_DIFF_1")
		)
		(pad "25" smd rect
			(at -4.42341 0.25019 90)
			(size 1.1684 0.3048)
			(layers "F.Cu" "F.Mask" "F.Paste")
			(net "VDD_IO_1")
		)
		(pad "26" smd rect
			(at -4.42341 0.75057 90)
			(size 1.1684 0.3048)
			(layers "F.Cu" "F.Mask" "F.Paste")
			(net "Net_307")
		)
		(pad "27" smd rect
			(at -4.42341 1.24968 90)
			(size 1.1684 0.3048)
			(layers "F.Cu" "F.Mask" "F.Paste")
			(net "Net_306")
		)
		(pad "28" smd rect
			(at -4.42341 1.75006 90)
			(size 1.1684 0.3048)
			(layers "F.Cu" "F.Mask" "F.Paste")
			(net "CLK_BUFFER_EU1_VOE_N")
		)
		(pad "29" smd rect
			(at -4.42341 2.25044 90)
			(size 1.1684 0.3048)
			(layers "F.Cu" "F.Mask" "F.Paste")
			(net "CLK_BUFFER_EU1_VOE_N")
		)
		(pad "30" smd rect
			(at -4.42341 2.74955 90)
			(size 1.1684 0.3048)
			(layers "F.Cu" "F.Mask" "F.Paste")
			(net "Net_305")
		)
		(pad "31" smd rect
			(at -4.42341 3.24993 90)
			(size 1.1684 0.3048)
			(layers "F.Cu" "F.Mask" "F.Paste")
			(net "Net_304")
		)
		(pad "32" smd rect
			(at -4.550918 3.75031 90)
			(size 0.9144 0.3048)
			(layers "F.Cu" "F.Mask" "F.Paste")
			(net "VDD_IO_1")
		)
		(pad "33" smd rect
			(at -3.75031 4.550918 90)
			(size 0.3048 0.9144)
			(layers "F.Cu" "F.Mask" "F.Paste")
			(net "GND")
		)
		(pad "34" smd rect
			(at -3.24993 4.42341 90)
			(size 0.3048 1.1684)
			(layers "F.Cu" "F.Mask" "F.Paste")
			(net "Net_323")
		)
		(pad "35" smd rect
			(at -2.74955 4.42341 90)
			(size 0.3048 1.1684)
			(layers "F.Cu" "F.Mask" "F.Paste")
			(net "Net_322")
		)
		(pad "36" smd rect
			(at -2.25044 4.42341 90)
			(size 0.3048 1.1684)
			(layers "F.Cu" "F.Mask" "F.Paste")
			(net "CLK_BUFFER_EU1_VOE_N")
		)
		(pad "37" smd rect
			(at -1.75006 4.42341 90)
			(size 0.3048 1.1684)
			(layers "F.Cu" "F.Mask" "F.Paste")
			(net "CLK_BUFFER_EU1_VOE_N")
		)
		(pad "38" smd rect
			(at -1.24968 4.42341 90)
			(size 0.3048 1.1684)
			(layers "F.Cu" "F.Mask" "F.Paste")
			(net "Net_321")
		)
		(pad "39" smd rect
			(at -0.75057 4.42341 90)
			(size 0.3048 1.1684)
			(layers "F.Cu" "F.Mask" "F.Paste")
			(net "Net_320")
		)
		(pad "40" smd rect
			(at -0.25019 4.42341 90)
			(size 0.3048 1.1684)
			(layers "F.Cu" "F.Mask" "F.Paste")
			(net "VDD_DIFF_1")
		)
		(pad "41" smd rect
			(at 0.25019 4.42341 90)
			(size 0.3048 1.1684)
			(layers "F.Cu" "F.Mask" "F.Paste")
			(net "GND")
		)
		(pad "42" smd rect
			(at 0.75057 4.42341 90)
			(size 0.3048 1.1684)
			(layers "F.Cu" "F.Mask" "F.Paste")
			(net "PE_CLK_100M_DR0_2_R_P")
		)
		(pad "43" smd rect
			(at 1.24968 4.42341 90)
			(size 0.3048 1.1684)
			(layers "F.Cu" "F.Mask" "F.Paste")
			(net "PE_CLK_100M_DR0_2_R_N")
		)
		(pad "44" smd rect
			(at 1.75006 4.42341 90)
			(size 0.3048 1.1684)
			(layers "F.Cu" "F.Mask" "F.Paste")
			(net "SSD_PRSNT0")
		)
		(pad "45" smd rect
			(at 2.25044 4.42341 90)
			(size 0.3048 1.1684)
			(layers "F.Cu" "F.Mask" "F.Paste")
			(net "SSD0_CLK0_OE_R_N")
		)
		(pad "46" smd rect
			(at 2.74955 4.42341 90)
			(size 0.3048 1.1684)
			(layers "F.Cu" "F.Mask" "F.Paste")
			(net "PE_CLK_100M_DR0_1_R_P")
		)
		(pad "47" smd rect
			(at 3.24993 4.42341 90)
			(size 0.3048 1.1684)
			(layers "F.Cu" "F.Mask" "F.Paste")
			(net "PE_CLK_100M_DR0_1_R_N")
		)
		(pad "48" smd rect
			(at 3.75031 4.550918 90)
			(size 0.3048 0.9144)
			(layers "F.Cu" "F.Mask" "F.Paste")
			(net "GND")
		)
		(pad "49" smd rect
			(at 4.550918 3.75031 90)
			(size 0.9144 0.3048)
			(layers "F.Cu" "F.Mask" "F.Paste")
			(net "VDD_IO_1")
		)
		(pad "50" smd rect
			(at 4.42341 3.24993 90)
			(size 1.1684 0.3048)
			(layers "F.Cu" "F.Mask" "F.Paste")
			(net "Net_1333")
		)
		(pad "51" smd rect
			(at 4.42341 2.74955 90)
			(size 1.1684 0.3048)
			(layers "F.Cu" "F.Mask" "F.Paste")
			(net "Net_1334")
		)
		(pad "52" smd rect
			(at 4.42341 2.25044 90)
			(size 1.1684 0.3048)
			(layers "F.Cu" "F.Mask" "F.Paste")
			(net "CLK_BUFFER_EU1_VOE_N")
		)
		(pad "53" smd rect
			(at 4.42341 1.75006 90)
			(size 1.1684 0.3048)
			(layers "F.Cu" "F.Mask" "F.Paste")
			(net "CLK_BUFFER_EU1_VOE_N")
		)
		(pad "54" smd rect
			(at 4.42341 1.24968 90)
			(size 1.1684 0.3048)
			(layers "F.Cu" "F.Mask" "F.Paste")
			(net "Net_1335")
		)
		(pad "55" smd rect
			(at 4.42341 0.75057 90)
			(size 1.1684 0.3048)
			(layers "F.Cu" "F.Mask" "F.Paste")
			(net "Net_1336")
		)
		(pad "56" smd rect
			(at 4.42341 0.25019 90)
			(size 1.1684 0.3048)
			(layers "F.Cu" "F.Mask" "F.Paste")
			(net "VDD_IO_1")
		)
		(pad "57" smd rect
			(at 4.42341 -0.25019 90)
			(size 1.1684 0.3048)
			(layers "F.Cu" "F.Mask" "F.Paste")
			(net "VDD_DIFF_1")
		)
		(pad "58" smd rect
			(at 4.42341 -0.75057 90)
			(size 1.1684 0.3048)
			(layers "F.Cu" "F.Mask" "F.Paste")
			(net "GND")
		)
		(pad "59" smd rect
			(at 4.42341 -1.24968 90)
			(size 1.1684 0.3048)
			(layers "F.Cu" "F.Mask" "F.Paste")
			(net "PE_CLK_100M_DR5_2_R_P")
		)
		(pad "60" smd rect
			(at 4.42341 -1.75006 90)
			(size 1.1684 0.3048)
			(layers "F.Cu" "F.Mask" "F.Paste")
			(net "PE_CLK_100M_DR5_2_R_N")
		)
		(pad "61" smd rect
			(at 4.42341 -2.25044 90)
			(size 1.1684 0.3048)
			(layers "F.Cu" "F.Mask" "F.Paste")
			(net "SSD_PRSNT5")
		)
		(pad "62" smd rect
			(at 4.42341 -2.74955 90)
			(size 1.1684 0.3048)
			(layers "F.Cu" "F.Mask" "F.Paste")
			(net "SSD5_CLK0_OE_R_N")
		)
		(pad "63" smd rect
			(at 4.42341 -3.24993 90)
			(size 1.1684 0.3048)
			(layers "F.Cu" "F.Mask" "F.Paste")
			(net "PE_CLK_100M_DR5_1_R_P")
		)
		(pad "64" smd rect
			(at 4.550918 -3.75031 90)
			(size 0.9144 0.3048)
			(layers "F.Cu" "F.Mask" "F.Paste")
			(net "PE_CLK_100M_DR5_1_R_N")
		)
		(pad "65" smd rect
			(at 0 0 90)
			(size 6.2484 6.2484)
			(layers "F.Cu" "F.Mask" "F.Paste")
			(net "GND")
		)
	)
	(footprint ""
		(layer "F.Cu")
		(at 233.045 -435.61 90)
		(property "Reference" "PR9079"
			(at 0 0 90)
			(layer "F.SilkS")
			(hide yes)
			(effects
				(font
					(size 1.27 1.27)
				)
			)
		)
		(property "Value" "10KR2F-2-GP"
			(at 0.064008 -3.993896 90)
			(unlocked yes)
			(layer "F.Fab")
			(hide yes)
			(effects
				(font
					(size 1.016 1.016)
					(thickness 0.1524)
				)
			)
		)
		(property "Device Type" "R402H16"
			(at 0.064008 -5.517896 90)
			(unlocked yes)
			(layer "F.Fab")
			(hide yes)
			(effects
				(font
					(size 1.016 1.016)
					(thickness 0.1524)
				)
			)
		)
		(duplicate_pad_numbers_are_jumpers no)
		(fp_line
			(start 0.508 -0.9398)
			(end -0.508 -0.9398)
			(stroke
				(width 0.1524)
				(type default)
			)
			(layer "F.SilkS")
		)
		(fp_line
			(start -0.508 -0.9398)
			(end -0.508 0.9398)
			(stroke
				(width 0.1524)
				(type default)
			)
			(layer "F.SilkS")
		)
		(fp_rect
			(start -0.508 0.9398)
			(end 0.508 -0.9398)
			(stroke
				(width 0)
				(type default)
			)
			(fill no)
			(layer "F.CrtYd")
		)
		(fp_rect
			(start -0.508 0.9398)
			(end 0.508 -0.9398)
			(stroke
				(width 0)
				(type default)
			)
			(fill no)
			(layer "F.Fab")
		)
		(pad "1" smd custom
			(at 0 -0.4445 90)
			(size 0.1397 0.1397)
			(layers "F.Cu" "F.Mask" "F.Paste")
			(net "P3V3_VRG5")
			(options
				(clearance outline)
				(anchor circle)
			)
			(primitives
				(gr_poly
					(pts
						(arc
							(start -0.1778 -0.2794)
							(mid -0.249642 -0.249642)
							(end -0.2794 -0.1778)
						)
						(arc
							(start -0.2794 0.1778)
							(mid -0.249642 0.249642)
							(end -0.1778 0.2794)
						)
						(arc
							(start 0.1778 0.2794)
							(mid 0.249642 0.249642)
							(end 0.2794 0.1778)
						)
						(arc
							(start 0.2794 -0.1778)
							(mid 0.249642 -0.249642)
							(end 0.1778 -0.2794)
						)
					)
					(width 0)
					(fill yes)
				)
			)
		)
		(pad "2" smd custom
			(at 0 0.4445 90)
			(size 0.1397 0.1397)
			(layers "F.Cu" "F.Mask" "F.Paste")
			(net "TPS53312_P3V3_PG")
			(options
				(clearance outline)
				(anchor circle)
			)
			(primitives
				(gr_poly
					(pts
						(arc
							(start -0.1778 -0.2794)
							(mid -0.249642 -0.249642)
							(end -0.2794 -0.1778)
						)
						(arc
							(start -0.2794 0.1778)
							(mid -0.249642 0.249642)
							(end -0.1778 0.2794)
						)
						(arc
							(start 0.1778 0.2794)
							(mid 0.249642 0.249642)
							(end 0.2794 0.1778)
						)
						(arc
							(start 0.2794 -0.1778)
							(mid 0.249642 -0.249642)
							(end 0.1778 -0.2794)
						)
					)
					(width 0)
					(fill yes)
				)
			)
		)
	)
)
